(kicad_pcb
	(version 20260206)
	(generator "pcbnew")
	(generator_version "10.0")
	(general
		(thickness 1.6)
		(legacy_teardrops no)
	)
	(paper "A4")
	(title_block
		(title "peb — Lightning_PEB_BRD.brd")
		(comment 1 "Lightning (Wiwynn / Facebook NVMe JBOF) / footprints 463-470 of 2563")
	)
	(layers
		(0 "F.Cu" signal "TOP")
		(4 "In1.Cu" signal "L2GND")
		(6 "In2.Cu" signal "L3")
		(8 "In3.Cu" signal "L4VCC")
		(10 "In4.Cu" signal "L5VCC")
		(12 "In5.Cu" signal "L6")
		(14 "In6.Cu" signal "L7GND")
		(2 "B.Cu" signal "BOTTOM")
		(9 "F.Adhes" user "F.Adhesive")
		(11 "B.Adhes" user "B.Adhesive")
		(13 "F.Paste" user "Package Geometry/Pastemask Top")
		(15 "B.Paste" user "Package Geometry/Pastemask Bottom")
		(5 "F.SilkS" user "Ref Des/Silkscreen Top")
		(7 "B.SilkS" user "Ref Des/Silkscreen Bottom")
		(1 "F.Mask" user "Board Geometry/Soldermask Top")
		(3 "B.Mask" user "Board Geometry/Soldermask Bottom")
		(17 "Dwgs.User" user "User.Drawings")
		(19 "Cmts.User" user "User.Comments")
		(21 "Eco1.User" user "User.Eco1")
		(23 "Eco2.User" user "User.Eco2")
		(25 "Edge.Cuts" user "Board Geometry/Outline")
		(27 "Margin" user)
		(31 "F.CrtYd" user "Package Geometry/Place Bound Top")
		(29 "B.CrtYd" user "Package Geometry/Place Bound Bottom")
		(35 "F.Fab" user "Ref Des/Assembly Top")
		(33 "B.Fab" user "Ref Des/Assembly Bottom")
	)
	(footprint ""
		(layer "F.Cu")
		(at 219.329 -9.144 90)
		(property "Reference" "R662"
			(at 0 0 90)
			(layer "F.SilkS")
			(hide yes)
			(effects
				(font
					(size 1.27 1.27)
				)
			)
		)
		(property "Value" "100KR2F-L1-GP"
			(at 0.064008 -3.993896 90)
			(unlocked yes)
			(layer "F.Fab")
			(hide yes)
			(effects
				(font
					(size 1.016 1.016)
					(thickness 0.1524)
				)
			)
		)
		(property "Device Type" "R402H16"
			(at 0.064008 -5.517896 90)
			(unlocked yes)
			(layer "F.Fab")
			(hide yes)
			(effects
				(font
					(size 1.016 1.016)
					(thickness 0.1524)
				)
			)
		)
		(duplicate_pad_numbers_are_jumpers no)
		(fp_line
			(start 0.508 -0.9398)
			(end -0.508 -0.9398)
			(stroke
				(width 0.1524)
				(type default)
			)
			(layer "F.SilkS")
		)
		(fp_line
			(start -0.508 -0.9398)
			(end -0.508 0.9398)
			(stroke
				(width 0.1524)
				(type default)
			)
			(layer "F.SilkS")
		)
		(fp_rect
			(start -0.508 0.9398)
			(end 0.508 -0.9398)
			(stroke
				(width 0)
				(type default)
			)
			(fill no)
			(layer "F.CrtYd")
		)
		(fp_rect
			(start -0.508 0.9398)
			(end 0.508 -0.9398)
			(stroke
				(width 0)
				(type default)
			)
			(fill no)
			(layer "F.Fab")
		)
		(pad "1" smd custom
			(at 0 -0.4445 90)
			(size 0.1397 0.1397)
			(layers "F.Cu" "F.Mask" "F.Paste")
			(net "P3V3_STBY")
			(options
				(clearance outline)
				(anchor circle)
			)
			(primitives
				(gr_poly
					(pts
						(arc
							(start -0.1778 -0.2794)
							(mid -0.249642 -0.249642)
							(end -0.2794 -0.1778)
						)
						(arc
							(start -0.2794 0.1778)
							(mid -0.249642 0.249642)
							(end -0.1778 0.2794)
						)
						(arc
							(start 0.1778 0.2794)
							(mid 0.249642 0.249642)
							(end 0.2794 0.1778)
						)
						(arc
							(start 0.2794 -0.1778)
							(mid 0.249642 -0.249642)
							(end 0.1778 -0.2794)
						)
					)
					(width 0)
					(fill yes)
				)
			)
		)
		(pad "2" smd custom
			(at 0 0.4445 90)
			(size 0.1397 0.1397)
			(layers "F.Cu" "F.Mask" "F.Paste")
			(net "EEPROM_A1")
			(options
				(clearance outline)
				(anchor circle)
			)
			(primitives
				(gr_poly
					(pts
						(arc
							(start -0.1778 -0.2794)
							(mid -0.249642 -0.249642)
							(end -0.2794 -0.1778)
						)
						(arc
							(start -0.2794 0.1778)
							(mid -0.249642 0.249642)
							(end -0.1778 0.2794)
						)
						(arc
							(start 0.1778 0.2794)
							(mid 0.249642 0.249642)
							(end 0.2794 0.1778)
						)
						(arc
							(start 0.2794 -0.1778)
							(mid 0.249642 -0.249642)
							(end 0.1778 -0.2794)
						)
					)
					(width 0)
					(fill yes)
				)
			)
		)
	)
	(footprint ""
		(layer "F.Cu")
		(at 337.058 -73.787 90)
		(property "Reference" "PR165"
			(at 0 0 90)
			(layer "F.SilkS")
			(hide yes)
			(effects
				(font
					(size 1.27 1.27)
				)
			)
		)
		(property "Value" "10KR2F-2-GP"
			(at 0.064008 -3.993896 90)
			(unlocked yes)
			(layer "F.Fab")
			(hide yes)
			(effects
				(font
					(size 1.016 1.016)
					(thickness 0.1524)
				)
			)
		)
		(property "Device Type" "R402H16"
			(at 0.064008 -5.517896 90)
			(unlocked yes)
			(layer "F.Fab")
			(hide yes)
			(effects
				(font
					(size 1.016 1.016)
					(thickness 0.1524)
				)
			)
		)
		(duplicate_pad_numbers_are_jumpers no)
		(fp_line
			(start 0.508 -0.9398)
			(end -0.508 -0.9398)
			(stroke
				(width 0.1524)
				(type default)
			)
			(layer "F.SilkS")
		)
		(fp_line
			(start -0.508 -0.9398)
			(end -0.508 0.9398)
			(stroke
				(width 0.1524)
				(type default)
			)
			(layer "F.SilkS")
		)
		(fp_rect
			(start -0.508 0.9398)
			(end 0.508 -0.9398)
			(stroke
				(width 0)
				(type default)
			)
			(fill no)
			(layer "F.CrtYd")
		)
		(fp_rect
			(start -0.508 0.9398)
			(end 0.508 -0.9398)
			(stroke
				(width 0)
				(type default)
			)
			(fill no)
			(layer "F.Fab")
		)
		(pad "1" smd custom
			(at 0 -0.4445 90)
			(size 0.1397 0.1397)
			(layers "F.Cu" "F.Mask" "F.Paste")
			(net "P0V9_E_VFB")
			(options
				(clearance outline)
				(anchor circle)
			)
			(primitives
				(gr_poly
					(pts
						(arc
							(start -0.1778 -0.2794)
							(mid -0.249642 -0.249642)
							(end -0.2794 -0.1778)
						)
						(arc
							(start -0.2794 0.1778)
							(mid -0.249642 0.249642)
							(end -0.1778 0.2794)
						)
						(arc
							(start 0.1778 0.2794)
							(mid 0.249642 0.249642)
							(end 0.2794 0.1778)
						)
						(arc
							(start 0.2794 -0.1778)
							(mid 0.249642 -0.249642)
							(end 0.1778 -0.2794)
						)
					)
					(width 0)
					(fill yes)
				)
			)
		)
		(pad "2" smd custom
			(at 0 0.4445 90)
			(size 0.1397 0.1397)
			(layers "F.Cu" "F.Mask" "F.Paste")
			(net "AGND_P0V9_E")
			(options
				(clearance outline)
				(anchor circle)
			)
			(primitives
				(gr_poly
					(pts
						(arc
							(start -0.1778 -0.2794)
							(mid -0.249642 -0.249642)
							(end -0.2794 -0.1778)
						)
						(arc
							(start -0.2794 0.1778)
							(mid -0.249642 0.249642)
							(end -0.1778 0.2794)
						)
						(arc
							(start 0.1778 0.2794)
							(mid 0.249642 0.249642)
							(end 0.2794 0.1778)
						)
						(arc
							(start 0.2794 -0.1778)
							(mid 0.249642 -0.249642)
							(end 0.1778 -0.2794)
						)
					)
					(width 0)
					(fill yes)
				)
			)
		)
	)
	(footprint ""
		(layer "F.Cu")
		(at 9.5631 -53.594 180)
		(property "Reference" "R597"
			(at 0 0 180)
			(layer "F.SilkS")
			(hide yes)
			(effects
				(font
					(size 1.27 1.27)
				)
			)
		)
		(property "Value" "0R2J-2-GP"
			(at 0.064008 -3.993896 180)
			(unlocked yes)
			(layer "F.Fab")
			(hide yes)
			(effects
				(font
					(size 1.016 1.016)
					(thickness 0.1524)
				)
			)
		)
		(property "Device Type" "R402H16"
			(at 0.064008 -5.517896 180)
			(unlocked yes)
			(layer "F.Fab")
			(hide yes)
			(effects
				(font
					(size 1.016 1.016)
					(thickness 0.1524)
				)
			)
		)
		(duplicate_pad_numbers_are_jumpers no)
		(fp_line
			(start 0.508 -0.9398)
			(end -0.508 -0.9398)
			(stroke
				(width 0.1524)
				(type default)
			)
			(layer "F.SilkS")
		)
		(fp_line
			(start -0.508 -0.9398)
			(end -0.508 0.9398)
			(stroke
				(width 0.1524)
				(type default)
			)
			(layer "F.SilkS")
		)
		(fp_rect
			(start -0.508 0.9398)
			(end 0.508 -0.9398)
			(stroke
				(width 0)
				(type default)
			)
			(fill no)
			(layer "F.CrtYd")
		)
		(fp_rect
			(start -0.508 0.9398)
			(end 0.508 -0.9398)
			(stroke
				(width 0)
				(type default)
			)
			(fill no)
			(layer "F.Fab")
		)
		(pad "1" smd custom
			(at 0 -0.4445 180)
			(size 0.1397 0.1397)
			(layers "F.Cu" "F.Mask" "F.Paste")
			(net "NIC0_MDI0_P0_R")
			(options
				(clearance outline)
				(anchor circle)
			)
			(primitives
				(gr_poly
					(pts
						(arc
							(start -0.1778 -0.2794)
							(mid -0.249642 -0.249642)
							(end -0.2794 -0.1778)
						)
						(arc
							(start -0.2794 0.1778)
							(mid -0.249642 0.249642)
							(end -0.1778 0.2794)
						)
						(arc
							(start 0.1778 0.2794)
							(mid 0.249642 0.249642)
							(end 0.2794 0.1778)
						)
						(arc
							(start 0.2794 -0.1778)
							(mid 0.249642 -0.249642)
							(end 0.1778 -0.2794)
						)
					)
					(width 0)
					(fill yes)
				)
			)
		)
		(pad "2" smd custom
			(at 0 0.4445 180)
			(size 0.1397 0.1397)
			(layers "F.Cu" "F.Mask" "F.Paste")
			(net "NIC0_MDI0_P0")
			(options
				(clearance outline)
				(anchor circle)
			)
			(primitives
				(gr_poly
					(pts
						(arc
							(start -0.1778 -0.2794)
							(mid -0.249642 -0.249642)
							(end -0.2794 -0.1778)
						)
						(arc
							(start -0.2794 0.1778)
							(mid -0.249642 0.249642)
							(end -0.1778 0.2794)
						)
						(arc
							(start 0.1778 0.2794)
							(mid 0.249642 0.249642)
							(end 0.2794 0.1778)
						)
						(arc
							(start 0.2794 -0.1778)
							(mid 0.249642 -0.249642)
							(end 0.1778 -0.2794)
						)
					)
					(width 0)
					(fill yes)
				)
			)
		)
	)
	(footprint ""
		(layer "F.Cu")
		(at 335.820512 -172.432218)
		(property "Reference" "R7967"
			(at 0 0 0)
			(layer "F.SilkS")
			(hide yes)
			(effects
				(font
					(size 1.27 1.27)
				)
			)
		)
		(property "Value" "0R2J-2-GP"
			(at 0.064008 -3.993896 0)
			(unlocked yes)
			(layer "F.Fab")
			(hide yes)
			(effects
				(font
					(size 1.016 1.016)
					(thickness 0.1524)
				)
			)
		)
		(property "Device Type" "R402H16"
			(at 0.064008 -5.517896 0)
			(unlocked yes)
			(layer "F.Fab")
			(hide yes)
			(effects
				(font
					(size 1.016 1.016)
					(thickness 0.1524)
				)
			)
		)
		(duplicate_pad_numbers_are_jumpers no)
		(fp_line
			(start -0.508 -0.9398)
			(end -0.508 0.9398)
			(stroke
				(width 0.1524)
				(type default)
			)
			(layer "F.SilkS")
		)
		(fp_line
			(start 0.508 -0.9398)
			(end -0.508 -0.9398)
			(stroke
				(width 0.1524)
				(type default)
			)
			(layer "F.SilkS")
		)
		(fp_rect
			(start -0.508 0.9398)
			(end 0.508 -0.9398)
			(stroke
				(width 0)
				(type default)
			)
			(fill no)
			(layer "F.CrtYd")
		)
		(fp_rect
			(start -0.508 0.9398)
			(end 0.508 -0.9398)
			(stroke
				(width 0)
				(type default)
			)
			(fill no)
			(layer "F.Fab")
		)
		(pad "1" smd custom
			(at 0 -0.4445)
			(size 0.1397 0.1397)
			(layers "F.Cu" "F.Mask" "F.Paste")
			(net "SSD_PERST#4")
			(options
				(clearance outline)
				(anchor circle)
			)
			(primitives
				(gr_poly
					(pts
						(arc
							(start -0.1778 -0.2794)
							(mid -0.249642 -0.249642)
							(end -0.2794 -0.1778)
						)
						(arc
							(start -0.2794 0.1778)
							(mid -0.249642 0.249642)
							(end -0.1778 0.2794)
						)
						(arc
							(start 0.1778 0.2794)
							(mid 0.249642 0.249642)
							(end 0.2794 0.1778)
						)
						(arc
							(start 0.2794 -0.1778)
							(mid 0.249642 -0.249642)
							(end 0.1778 -0.2794)
						)
					)
					(width 0)
					(fill yes)
				)
			)
		)
		(pad "2" smd custom
			(at 0 0.4445)
			(size 0.1397 0.1397)
			(layers "F.Cu" "F.Mask" "F.Paste")
			(net "SSD_PERST#4_R")
			(options
				(clearance outline)
				(anchor circle)
			)
			(primitives
				(gr_poly
					(pts
						(arc
							(start -0.1778 -0.2794)
							(mid -0.249642 -0.249642)
							(end -0.2794 -0.1778)
						)
						(arc
							(start -0.2794 0.1778)
							(mid -0.249642 0.249642)
							(end -0.1778 0.2794)
						)
						(arc
							(start 0.1778 0.2794)
							(mid 0.249642 0.249642)
							(end 0.2794 0.1778)
						)
						(arc
							(start 0.2794 -0.1778)
							(mid 0.249642 -0.249642)
							(end 0.1778 -0.2794)
						)
					)
					(width 0)
					(fill yes)
				)
			)
		)
	)
	(footprint ""
		(layer "F.Cu")
		(at 25.95626 -81.22412 90)
		(property "Reference" "R387"
			(at 0 0 90)
			(layer "F.SilkS")
			(hide yes)
			(effects
				(font
					(size 1.27 1.27)
				)
			)
		)
		(property "Value" "0R2J-2-GP"
			(at 0.064008 -3.993896 90)
			(unlocked yes)
			(layer "F.Fab")
			(hide yes)
			(effects
				(font
					(size 1.016 1.016)
					(thickness 0.1524)
				)
			)
		)
		(property "Device Type" "R402H16"
			(at 0.064008 -5.517896 90)
			(unlocked yes)
			(layer "F.Fab")
			(hide yes)
			(effects
				(font
					(size 1.016 1.016)
					(thickness 0.1524)
				)
			)
		)
		(duplicate_pad_numbers_are_jumpers no)
		(fp_line
			(start 0.508 -0.9398)
			(end -0.508 -0.9398)
			(stroke
				(width 0.1524)
				(type default)
			)
			(layer "F.SilkS")
		)
		(fp_line
			(start -0.508 -0.9398)
			(end -0.508 0.9398)
			(stroke
				(width 0.1524)
				(type default)
			)
			(layer "F.SilkS")
		)
		(fp_rect
			(start -0.508 0.9398)
			(end 0.508 -0.9398)
			(stroke
				(width 0)
				(type default)
			)
			(fill no)
			(layer "F.CrtYd")
		)
		(fp_rect
			(start -0.508 0.9398)
			(end 0.508 -0.9398)
			(stroke
				(width 0)
				(type default)
			)
			(fill no)
			(layer "F.Fab")
		)
		(pad "1" smd custom
			(at 0 -0.4445 90)
			(size 0.1397 0.1397)
			(layers "F.Cu" "F.Mask" "F.Paste")
			(net "NVM_SK")
			(options
				(clearance outline)
				(anchor circle)
			)
			(primitives
				(gr_poly
					(pts
						(arc
							(start -0.1778 -0.2794)
							(mid -0.249642 -0.249642)
							(end -0.2794 -0.1778)
						)
						(arc
							(start -0.2794 0.1778)
							(mid -0.249642 0.249642)
							(end -0.1778 0.2794)
						)
						(arc
							(start 0.1778 0.2794)
							(mid 0.249642 0.249642)
							(end 0.2794 0.1778)
						)
						(arc
							(start 0.2794 -0.1778)
							(mid 0.249642 -0.249642)
							(end 0.1778 -0.2794)
						)
					)
					(width 0)
					(fill yes)
				)
			)
		)
		(pad "2" smd custom
			(at 0 0.4445 90)
			(size 0.1397 0.1397)
			(layers "F.Cu" "F.Mask" "F.Paste")
			(net "I210_SK_R")
			(options
				(clearance outline)
				(anchor circle)
			)
			(primitives
				(gr_poly
					(pts
						(arc
							(start -0.1778 -0.2794)
							(mid -0.249642 -0.249642)
							(end -0.2794 -0.1778)
						)
						(arc
							(start -0.2794 0.1778)
							(mid -0.249642 0.249642)
							(end -0.1778 0.2794)
						)
						(arc
							(start 0.1778 0.2794)
							(mid 0.249642 0.249642)
							(end 0.2794 0.1778)
						)
						(arc
							(start 0.2794 -0.1778)
							(mid 0.249642 -0.249642)
							(end 0.1778 -0.2794)
						)
					)
					(width 0)
					(fill yes)
				)
			)
		)
	)
	(footprint ""
		(layer "F.Cu")
		(at 326.517 -99.568 180)
		(property "Reference" "R4171"
			(at 0 0 180)
			(layer "F.SilkS")
			(hide yes)
			(effects
				(font
					(size 1.27 1.27)
				)
			)
		)
		(property "Value" "4K7R2F-GP"
			(at 0.064008 -3.993896 180)
			(unlocked yes)
			(layer "F.Fab")
			(hide yes)
			(effects
				(font
					(size 1.016 1.016)
					(thickness 0.1524)
				)
			)
		)
		(property "Device Type" "R402H16"
			(at 0.064008 -5.517896 180)
			(unlocked yes)
			(layer "F.Fab")
			(hide yes)
			(effects
				(font
					(size 1.016 1.016)
					(thickness 0.1524)
				)
			)
		)
		(duplicate_pad_numbers_are_jumpers no)
		(fp_line
			(start 0.508 -0.9398)
			(end -0.508 -0.9398)
			(stroke
				(width 0.1524)
				(type default)
			)
			(layer "F.SilkS")
		)
		(fp_line
			(start -0.508 -0.9398)
			(end -0.508 0.9398)
			(stroke
				(width 0.1524)
				(type default)
			)
			(layer "F.SilkS")
		)
		(fp_rect
			(start -0.508 0.9398)
			(end 0.508 -0.9398)
			(stroke
				(width 0)
				(type default)
			)
			(fill no)
			(layer "F.CrtYd")
		)
		(fp_rect
			(start -0.508 0.9398)
			(end 0.508 -0.9398)
			(stroke
				(width 0)
				(type default)
			)
			(fill no)
			(layer "F.Fab")
		)
		(pad "1" smd custom
			(at 0 -0.4445 180)
			(size 0.1397 0.1397)
			(layers "F.Cu" "F.Mask" "F.Paste")
			(net "VS6_LED")
			(options
				(clearance outline)
				(anchor circle)
			)
			(primitives
				(gr_poly
					(pts
						(arc
							(start -0.1778 -0.2794)
							(mid -0.249642 -0.249642)
							(end -0.2794 -0.1778)
						)
						(arc
							(start -0.2794 0.1778)
							(mid -0.249642 0.249642)
							(end -0.1778 0.2794)
						)
						(arc
							(start 0.1778 0.2794)
							(mid 0.249642 0.249642)
							(end 0.2794 0.1778)
						)
						(arc
							(start 0.2794 -0.1778)
							(mid 0.249642 -0.249642)
							(end 0.1778 -0.2794)
						)
					)
					(width 0)
					(fill yes)
				)
			)
		)
		(pad "2" smd custom
			(at 0 0.4445 180)
			(size 0.1397 0.1397)
			(layers "F.Cu" "F.Mask" "F.Paste")
			(net "P3V3_STBY")
			(options
				(clearance outline)
				(anchor circle)
			)
			(primitives
				(gr_poly
					(pts
						(arc
							(start -0.1778 -0.2794)
							(mid -0.249642 -0.249642)
							(end -0.2794 -0.1778)
						)
						(arc
							(start -0.2794 0.1778)
							(mid -0.249642 0.249642)
							(end -0.1778 0.2794)
						)
						(arc
							(start 0.1778 0.2794)
							(mid 0.249642 0.249642)
							(end 0.2794 0.1778)
						)
						(arc
							(start 0.2794 -0.1778)
							(mid 0.249642 -0.249642)
							(end 0.1778 -0.2794)
						)
					)
					(width 0)
					(fill yes)
				)
			)
		)
	)
	(footprint ""
		(layer "F.Cu")
		(at 150.375874 -86.25332)
		(property "Reference" "PG10"
			(at 0 0 0)
			(layer "F.SilkS")
			(hide yes)
			(effects
				(font
					(size 1.27 1.27)
				)
			)
		)
		(property "Value" "GAP-CLOSE-PWR-3-GP"
			(at 0.0254 -6.5786 0)
			(unlocked yes)
			(layer "F.Fab")
			(hide yes)
			(effects
				(font
					(size 1.016 1.016)
					(thickness 0.1524)
				)
			)
		)
		(property "Device Type" "GAP-CLOSE-PWR-3"
			(at 0.0254 -8.255 0)
			(unlocked yes)
			(layer "F.Fab")
			(hide yes)
			(effects
				(font
					(size 1.016 1.016)
					(thickness 0.1524)
				)
			)
		)
		(duplicate_pad_numbers_are_jumpers no)
		(fp_rect
			(start -0.7112 0.4572)
			(end 0.7112 -0.4572)
			(stroke
				(width 0)
				(type default)
			)
			(fill no)
			(layer "F.CrtYd")
		)
		(fp_poly
			(pts
				(xy -0.7112 -0.4572) (xy 0.7112 -0.4572) (xy 0.7112 0.4572) (xy -0.7112 0.4572)
			)
			(stroke
				(width 0)
				(type default)
			)
			(fill no)
			(layer "F.Fab")
		)
		(pad "1" smd rect
			(at -0.3048 0)
			(size 0.6604 0.762)
			(layers "F.Cu" "F.Mask" "F.Paste")
			(net "P1V8_PWR")
		)
		(pad "2" smd rect
			(at 0.3048 0)
			(size 0.6604 0.762)
			(layers "F.Cu" "F.Mask" "F.Paste")
			(net "P1V8_STBY")
		)
	)
	(footprint ""
		(layer "F.Cu")
		(at 217.996008 -4.064)
		(property "Reference" "SC1114"
			(at 0 0 0)
			(layer "F.SilkS")
			(hide yes)
			(effects
				(font
					(size 1.27 1.27)
				)
			)
		)
		(property "Value" "SCD1U16V2KX-3GP"
			(at 1.1811 -2.7051 0)
			(unlocked yes)
			(layer "F.Fab")
			(hide yes)
			(effects
				(font
					(size 1.016 1.016)
					(thickness 0.1524)
				)
			)
		)
		(property "Device Type" "C402H22"
			(at 1.1811 -4.2291 0)
			(unlocked yes)
			(layer "F.Fab")
			(hide yes)
			(effects
				(font
					(size 1.016 1.016)
					(thickness 0.1524)
				)
			)
		)
		(duplicate_pad_numbers_are_jumpers no)
		(fp_rect
			(start -0.4318 0.9525)
			(end 0.4318 -0.9525)
			(stroke
				(width 0)
				(type default)
			)
			(fill no)
			(layer "F.CrtYd")
		)
		(fp_rect
			(start -0.4318 0.9525)
			(end 0.4318 -0.9525)
			(stroke
				(width 0)
				(type default)
			)
			(fill no)
			(layer "F.Fab")
		)
		(pad "1" smd custom
			(at 0 -0.4445)
			(size 0.1524 0.1524)
			(layers "F.Cu" "F.Mask" "F.Paste")
			(net "P3V3_STBY")
			(options
				(clearance outline)
				(anchor circle)
			)
			(primitives
				(gr_poly
					(pts
						(arc
							(start 0.3048 -0.2032)
							(mid 0.275042 -0.275042)
							(end 0.2032 -0.3048)
						)
						(arc
							(start -0.2032 -0.3048)
							(mid -0.275042 -0.275042)
							(end -0.3048 -0.2032)
						)
						(arc
							(start -0.3048 0.2032)
							(mid -0.275042 0.275042)
							(end -0.2032 0.3048)
						)
						(arc
							(start 0.2032 0.3048)
							(mid 0.275042 0.275042)
							(end 0.3048 0.2032)
						)
					)
					(width 0)
					(fill yes)
				)
			)
		)
		(pad "2" smd custom
			(at 0 0.4445)
			(size 0.1524 0.1524)
			(layers "F.Cu" "F.Mask" "F.Paste")
			(net "GND")
			(options
				(clearance outline)
				(anchor circle)
			)
			(primitives
				(gr_poly
					(pts
						(arc
							(start 0.3048 -0.2032)
							(mid 0.275042 -0.275042)
							(end 0.2032 -0.3048)
						)
						(arc
							(start -0.2032 -0.3048)
							(mid -0.275042 -0.275042)
							(end -0.3048 -0.2032)
						)
						(arc
							(start -0.3048 0.2032)
							(mid -0.275042 0.275042)
							(end -0.2032 0.3048)
						)
						(arc
							(start 0.2032 0.3048)
							(mid 0.275042 0.275042)
							(end 0.3048 0.2032)
						)
					)
					(width 0)
					(fill yes)
				)
			)
		)
	)
)
